(kicad_pcb
	(version 20260206)
	(generator "pcbnew")
	(generator_version "10.0")
	(general
		(thickness 1.6)
		(legacy_teardrops no)
	)
	(paper "A4")
	(title_block
		(title "Bryce Canyon_IOM_IOC_16318-2_OCP.brd")
		(comment 1 "Bryce Canyon / footprints 111-117 of 1605")
	)
	(layers
		(0 "F.Cu" signal "TOP")
		(4 "In1.Cu" signal "L2GND")
		(6 "In2.Cu" signal "L3")
		(8 "In3.Cu" signal "L4VCC")
		(10 "In4.Cu" signal "L5VCC")
		(12 "In5.Cu" signal "L6")
		(14 "In6.Cu" signal "L7GND")
		(2 "B.Cu" signal "BOTTOM")
		(9 "F.Adhes" user "F.Adhesive")
		(11 "B.Adhes" user "B.Adhesive")
		(13 "F.Paste" user "Package Geometry/Pastemask Top")
		(15 "B.Paste" user "Package Geometry/Pastemask Bottom")
		(5 "F.SilkS" user "Ref Des/Silkscreen Top")
		(7 "B.SilkS" user "Ref Des/Silkscreen Bottom")
		(1 "F.Mask" user "Board Geometry/Soldermask Top")
		(3 "B.Mask" user "Board Geometry/Soldermask Bottom")
		(17 "Dwgs.User" user "User.Drawings")
		(19 "Cmts.User" user "User.Comments")
		(21 "Eco1.User" user "User.Eco1")
		(23 "Eco2.User" user "User.Eco2")
		(25 "Edge.Cuts" user "Board Geometry/Outline")
		(27 "Margin" user)
		(31 "F.CrtYd" user "Package Geometry/Place Bound Top")
		(29 "B.CrtYd" user "Package Geometry/Place Bound Bottom")
		(35 "F.Fab" user "Ref Des/Assembly Top")
		(33 "B.Fab" user "Ref Des/Assembly Bottom")
	)
	(footprint ""
		(layer "F.Cu")
		(at 159.29864 -136.662922)
		(property "Reference" "PU4"
			(at 0 0 0)
			(layer "F.SilkS")
			(hide yes)
			(effects
				(font
					(size 1.27 1.27)
				)
			)
		)
		(property "Value" "TPS53312RGTR-GP"
			(at 4.9784 -6.9342 0)
			(unlocked yes)
			(layer "F.Fab")
			(hide yes)
			(effects
				(font
					(size 1.016 1.016)
					(thickness 0.1524)
				)
			)
		)
		(property "Device Type" "QFN16G3-G1D7H40"
			(at 4.9784 -8.4582 0)
			(unlocked yes)
			(layer "F.Fab")
			(hide yes)
			(effects
				(font
					(size 1.016 1.016)
					(thickness 0.1524)
				)
			)
		)
		(duplicate_pad_numbers_are_jumpers no)
		(fp_line
			(start -2.5146 -2.5146)
			(end -2.5146 -1.2446)
			(stroke
				(width 0.1524)
				(type default)
			)
			(layer "F.SilkS")
		)
		(fp_line
			(start -2.5146 1.2446)
			(end -2.5146 2.5146)
			(stroke
				(width 0.1524)
				(type default)
			)
			(layer "F.SilkS")
		)
		(fp_line
			(start -2.5146 2.5146)
			(end -1.2446 2.5146)
			(stroke
				(width 0.1524)
				(type default)
			)
			(layer "F.SilkS")
		)
		(fp_line
			(start -2.262124 -0.750062)
			(end -2.770124 -0.750062)
			(stroke
				(width 0.1524)
				(type default)
			)
			(layer "F.SilkS")
		)
		(fp_line
			(start -1.2446 -2.5146)
			(end -2.5146 -2.5146)
			(stroke
				(width 0.1524)
				(type default)
			)
			(layer "F.SilkS")
		)
		(fp_line
			(start -0.249936 2.262124)
			(end -0.249936 3.024124)
			(stroke
				(width 0.1524)
				(type default)
			)
			(layer "F.SilkS")
		)
		(fp_line
			(start 1.2446 2.5146)
			(end 2.5146 2.5146)
			(stroke
				(width 0.1524)
				(type default)
			)
			(layer "F.SilkS")
		)
		(fp_line
			(start 2.262124 -0.249936)
			(end 2.770124 -0.249936)
			(stroke
				(width 0.1524)
				(type default)
			)
			(layer "F.SilkS")
		)
		(fp_line
			(start 2.5146 2.5146)
			(end 2.5146 1.2446)
			(stroke
				(width 0.1524)
				(type default)
			)
			(layer "F.SilkS")
		)
		(fp_poly
			(pts
				(xy 2.5146 -2.5146) (xy 1.2446 -2.5146) (xy 2.5146 -1.2446)
			)
			(stroke
				(width 0)
				(type default)
			)
			(fill yes)
			(layer "F.SilkS")
		)
		(fp_rect
			(start -1.4986 1.4986)
			(end 1.4986 -1.4986)
			(stroke
				(width 0)
				(type default)
			)
			(fill no)
			(layer "F.CrtYd")
		)
		(fp_poly
			(pts
				(xy 2.5146 -1.4986) (xy -1.4986 -1.4986) (xy -1.4986 1.4986) (xy 1.4986 1.4986) (xy 1.4986 -1.4859)
				(xy 2.5146 -1.4859) (xy 2.5146 2.5146) (xy -2.5146 2.5146) (xy -2.5146 -2.5146) (xy 2.5146 -2.5146)
			)
			(stroke
				(width 0)
				(type default)
			)
			(fill no)
			(layer "F.CrtYd")
		)
		(fp_rect
			(start -2.5146 2.5146)
			(end 2.5146 -2.5146)
			(stroke
				(width 0)
				(type default)
			)
			(fill no)
			(layer "F.Fab")
		)
		(pad "1" smd rect
			(at 0.750062 -1.550924)
			(size 0.3048 0.9144)
			(layers "F.Cu" "F.Mask" "F.Paste")
			(net "P1V8_STBY_VFB")
		)
		(pad "2" smd rect
			(at 0.249936 -1.538224)
			(size 0.3048 0.9398)
			(layers "F.Cu" "F.Mask" "F.Paste")
			(net "P1V8_STBY_VRG5")
		)
		(pad "3" smd rect
			(at -0.249936 -1.538224)
			(size 0.3048 0.9398)
			(layers "F.Cu" "F.Mask" "F.Paste")
			(net "P1V8_STBY_SS")
		)
		(pad "4" smd rect
			(at -0.750062 -1.550924)
			(size 0.3048 0.9144)
			(layers "F.Cu" "F.Mask" "F.Paste")
			(net "AGND_P1V8_STBY")
		)
		(pad "5" smd rect
			(at -1.550924 -0.750062)
			(size 0.9144 0.3048)
			(layers "F.Cu" "F.Mask" "F.Paste")
			(net "PWRGD_P1V8_STBY")
		)
		(pad "6" smd rect
			(at -1.538224 -0.249936)
			(size 0.9398 0.3048)
			(layers "F.Cu" "F.Mask" "F.Paste")
			(net "P1V8_STBY_EN_R")
		)
		(pad "7" smd rect
			(at -1.538224 0.249936)
			(size 0.9398 0.3048)
			(layers "F.Cu" "F.Mask" "F.Paste")
			(net "GND")
		)
		(pad "8" smd rect
			(at -1.550924 0.750062)
			(size 0.9144 0.3048)
			(layers "F.Cu" "F.Mask" "F.Paste")
			(net "GND")
		)
		(pad "9" smd rect
			(at -0.750062 1.550924)
			(size 0.3048 0.9144)
			(layers "F.Cu" "F.Mask" "F.Paste")
			(net "P1V8_STBY_SW")
		)
		(pad "10" smd rect
			(at -0.249936 1.538224)
			(size 0.3048 0.9398)
			(layers "F.Cu" "F.Mask" "F.Paste")
			(net "P1V8_STBY_SW")
		)
		(pad "11" smd rect
			(at 0.249936 1.538224)
			(size 0.3048 0.9398)
			(layers "F.Cu" "F.Mask" "F.Paste")
			(net "P1V8_STBY_SW")
		)
		(pad "12" smd rect
			(at 0.750062 1.550924)
			(size 0.3048 0.9144)
			(layers "F.Cu" "F.Mask" "F.Paste")
			(net "P1V8_STBY_VBST")
		)
		(pad "13" smd rect
			(at 1.550924 0.750062)
			(size 0.9144 0.3048)
			(layers "F.Cu" "F.Mask" "F.Paste")
			(net "P12V_STBY_VIN_PU4")
		)
		(pad "14" smd rect
			(at 1.538224 0.249936)
			(size 0.9398 0.3048)
			(layers "F.Cu" "F.Mask" "F.Paste")
			(net "P12V_STBY_VIN_PU4")
		)
		(pad "15" smd rect
			(at 1.538224 -0.249936)
			(size 0.9398 0.3048)
			(layers "F.Cu" "F.Mask" "F.Paste")
			(net "P12V_STBY_VCC_PU4")
		)
		(pad "16" smd rect
			(at 1.550924 -0.750062)
			(size 0.9144 0.3048)
			(layers "F.Cu" "F.Mask" "F.Paste")
			(net "P1V8_STBY_VO")
		)
		(pad "17" smd rect
			(at 0 0)
			(size 1.6764 1.6764)
			(layers "F.Cu" "F.Mask" "F.Paste")
			(net "GND")
		)
	)
	(footprint ""
		(layer "F.Cu")
		(at 57.785 -163.5252 180)
		(property "Reference" "C120"
			(at 0 0 180)
			(layer "F.SilkS")
			(hide yes)
			(effects
				(font
					(size 1.27 1.27)
				)
			)
		)
		(property "Value" "SCD1U25V2KX-2-GP"
			(at 1.1811 -2.7051 180)
			(unlocked yes)
			(layer "F.Fab")
			(hide yes)
			(effects
				(font
					(size 1.016 1.016)
					(thickness 0.1524)
				)
			)
		)
		(property "Device Type" "C402H22"
			(at 1.1811 -4.2291 180)
			(unlocked yes)
			(layer "F.Fab")
			(hide yes)
			(effects
				(font
					(size 1.016 1.016)
					(thickness 0.1524)
				)
			)
		)
		(duplicate_pad_numbers_are_jumpers no)
		(fp_rect
			(start -0.4318 0.9525)
			(end 0.4318 -0.9525)
			(stroke
				(width 0)
				(type default)
			)
			(fill no)
			(layer "F.CrtYd")
		)
		(fp_rect
			(start -0.4318 0.9525)
			(end 0.4318 -0.9525)
			(stroke
				(width 0)
				(type default)
			)
			(fill no)
			(layer "F.Fab")
		)
		(pad "1" smd custom
			(at 0 -0.4445 180)
			(size 0.1524 0.1524)
			(layers "F.Cu" "F.Mask" "F.Paste")
			(net "ADC_P3V3_STBY")
			(options
				(clearance outline)
				(anchor circle)
			)
			(primitives
				(gr_poly
					(pts
						(arc
							(start 0.3048 -0.2032)
							(mid 0.275042 -0.275042)
							(end 0.2032 -0.3048)
						)
						(arc
							(start -0.2032 -0.3048)
							(mid -0.275042 -0.275042)
							(end -0.3048 -0.2032)
						)
						(arc
							(start -0.3048 0.2032)
							(mid -0.275042 0.275042)
							(end -0.2032 0.3048)
						)
						(arc
							(start 0.2032 0.3048)
							(mid 0.275042 0.275042)
							(end 0.3048 0.2032)
						)
					)
					(width 0)
					(fill yes)
				)
			)
		)
		(pad "2" smd custom
			(at 0 0.4445 180)
			(size 0.1524 0.1524)
			(layers "F.Cu" "F.Mask" "F.Paste")
			(net "GND")
			(options
				(clearance outline)
				(anchor circle)
			)
			(primitives
				(gr_poly
					(pts
						(arc
							(start 0.3048 -0.2032)
							(mid 0.275042 -0.275042)
							(end 0.2032 -0.3048)
						)
						(arc
							(start -0.2032 -0.3048)
							(mid -0.275042 -0.275042)
							(end -0.3048 -0.2032)
						)
						(arc
							(start -0.3048 0.2032)
							(mid -0.275042 0.275042)
							(end -0.2032 0.3048)
						)
						(arc
							(start 0.2032 0.3048)
							(mid 0.275042 0.275042)
							(end 0.3048 0.2032)
						)
					)
					(width 0)
					(fill yes)
				)
			)
		)
	)
	(footprint ""
		(layer "F.Cu")
		(at 61.1886 -139.0142)
		(property "Reference" "TP75"
			(at 0 0 0)
			(layer "F.SilkS")
			(hide yes)
			(effects
				(font
					(size 1.27 1.27)
				)
			)
		)
		(property "Value" "TPAD28-2-GP"
			(at -0.0127 -1.6637 0)
			(unlocked yes)
			(layer "F.Fab")
			(hide yes)
			(effects
				(font
					(size 1.016 1.016)
					(thickness 0.1524)
				)
			)
		)
		(property "Device Type" "TPAD28"
			(at -0.0127 -3.1877 0)
			(unlocked yes)
			(layer "F.Fab")
			(hide yes)
			(effects
				(font
					(size 1.016 1.016)
					(thickness 0.1524)
				)
			)
		)
		(duplicate_pad_numbers_are_jumpers no)
		(fp_poly
			(pts
				(arc
					(start 0.3556 0)
					(mid -0.3556 0)
					(end 0.3556 0)
				)
			)
			(stroke
				(width 0)
				(type default)
			)
			(fill no)
			(layer "F.CrtYd")
		)
		(fp_poly
			(pts
				(arc
					(start 0.6096 0)
					(mid -0.6096 0)
					(end 0.6096 0)
				)
			)
			(stroke
				(width 0)
				(type default)
			)
			(fill no)
			(layer "F.Fab")
		)
		(pad "1" smd circle
			(at 0 0)
			(size 0.7112 0.7112)
			(layers "F.Cu" "F.Mask" "F.Paste")
			(net "TP_BMC_GPIOI6")
		)
	)
	(footprint ""
		(layer "F.Cu")
		(at 224.3074 -56.6166)
		(property "Reference" "C306"
			(at 0 0 0)
			(layer "F.SilkS")
			(hide yes)
			(effects
				(font
					(size 1.27 1.27)
				)
			)
		)
		(property "Value" "SC12P50V2JN-3GP"
			(at 1.1811 -2.7051 0)
			(unlocked yes)
			(layer "F.Fab")
			(hide yes)
			(effects
				(font
					(size 1.016 1.016)
					(thickness 0.1524)
				)
			)
		)
		(property "Device Type" "C402H24"
			(at 1.1811 -4.2291 0)
			(unlocked yes)
			(layer "F.Fab")
			(hide yes)
			(effects
				(font
					(size 1.016 1.016)
					(thickness 0.1524)
				)
			)
		)
		(duplicate_pad_numbers_are_jumpers no)
		(fp_rect
			(start -0.4318 0.9525)
			(end 0.4318 -0.9525)
			(stroke
				(width 0)
				(type default)
			)
			(fill no)
			(layer "F.CrtYd")
		)
		(fp_rect
			(start -0.4318 0.9525)
			(end 0.4318 -0.9525)
			(stroke
				(width 0)
				(type default)
			)
			(fill no)
			(layer "F.Fab")
		)
		(pad "1" smd custom
			(at 0 -0.4445)
			(size 0.1524 0.1524)
			(layers "F.Cu" "F.Mask" "F.Paste")
			(net "REF_CLK")
			(options
				(clearance outline)
				(anchor circle)
			)
			(primitives
				(gr_poly
					(pts
						(arc
							(start 0.3048 -0.2032)
							(mid 0.275042 -0.275042)
							(end 0.2032 -0.3048)
						)
						(arc
							(start -0.2032 -0.3048)
							(mid -0.275042 -0.275042)
							(end -0.3048 -0.2032)
						)
						(arc
							(start -0.3048 0.2032)
							(mid -0.275042 0.275042)
							(end -0.2032 0.3048)
						)
						(arc
							(start 0.2032 0.3048)
							(mid 0.275042 0.275042)
							(end 0.3048 0.2032)
						)
					)
					(width 0)
					(fill yes)
				)
			)
		)
		(pad "2" smd custom
			(at 0 0.4445)
			(size 0.1524 0.1524)
			(layers "F.Cu" "F.Mask" "F.Paste")
			(net "GND")
			(options
				(clearance outline)
				(anchor circle)
			)
			(primitives
				(gr_poly
					(pts
						(arc
							(start 0.3048 -0.2032)
							(mid 0.275042 -0.275042)
							(end 0.2032 -0.3048)
						)
						(arc
							(start -0.2032 -0.3048)
							(mid -0.275042 -0.275042)
							(end -0.3048 -0.2032)
						)
						(arc
							(start -0.3048 0.2032)
							(mid -0.275042 0.275042)
							(end -0.2032 0.3048)
						)
						(arc
							(start 0.2032 0.3048)
							(mid 0.275042 0.275042)
							(end 0.3048 0.2032)
						)
					)
					(width 0)
					(fill yes)
				)
			)
		)
	)
	(footprint ""
		(layer "F.Cu")
		(at 64.077088 -156.179774)
		(property "Reference" "R382"
			(at 0 0 0)
			(layer "F.SilkS")
			(hide yes)
			(effects
				(font
					(size 1.27 1.27)
				)
			)
		)
		(property "Value" "4K7R2F-GP"
			(at 0.064008 -3.993896 0)
			(unlocked yes)
			(layer "F.Fab")
			(hide yes)
			(effects
				(font
					(size 1.016 1.016)
					(thickness 0.1524)
				)
			)
		)
		(property "Device Type" "R402H16"
			(at 0.064008 -5.517896 0)
			(unlocked yes)
			(layer "F.Fab")
			(hide yes)
			(effects
				(font
					(size 1.016 1.016)
					(thickness 0.1524)
				)
			)
		)
		(duplicate_pad_numbers_are_jumpers no)
		(fp_line
			(start -0.508 -0.9398)
			(end -0.508 0.9398)
			(stroke
				(width 0.1524)
				(type default)
			)
			(layer "F.SilkS")
		)
		(fp_line
			(start 0.508 -0.9398)
			(end -0.508 -0.9398)
			(stroke
				(width 0.1524)
				(type default)
			)
			(layer "F.SilkS")
		)
		(fp_rect
			(start -0.508 0.9398)
			(end 0.508 -0.9398)
			(stroke
				(width 0)
				(type default)
			)
			(fill no)
			(layer "F.CrtYd")
		)
		(fp_rect
			(start -0.508 0.9398)
			(end 0.508 -0.9398)
			(stroke
				(width 0)
				(type default)
			)
			(fill no)
			(layer "F.Fab")
		)
		(pad "1" smd custom
			(at 0 -0.4445)
			(size 0.1397 0.1397)
			(layers "F.Cu" "F.Mask" "F.Paste")
			(net "P3V3_STBY")
			(options
				(clearance outline)
				(anchor circle)
			)
			(primitives
				(gr_poly
					(pts
						(arc
							(start -0.1778 -0.2794)
							(mid -0.249642 -0.249642)
							(end -0.2794 -0.1778)
						)
						(arc
							(start -0.2794 0.1778)
							(mid -0.249642 0.249642)
							(end -0.1778 0.2794)
						)
						(arc
							(start 0.1778 0.2794)
							(mid 0.249642 0.249642)
							(end 0.2794 0.1778)
						)
						(arc
							(start 0.2794 -0.1778)
							(mid 0.249642 -0.249642)
							(end 0.1778 -0.2794)
						)
					)
					(width 0)
					(fill yes)
				)
			)
		)
		(pad "2" smd custom
			(at 0 0.4445)
			(size 0.1397 0.1397)
			(layers "F.Cu" "F.Mask" "F.Paste")
			(net "NCSI_TXD1")
			(options
				(clearance outline)
				(anchor circle)
			)
			(primitives
				(gr_poly
					(pts
						(arc
							(start -0.1778 -0.2794)
							(mid -0.249642 -0.249642)
							(end -0.2794 -0.1778)
						)
						(arc
							(start -0.2794 0.1778)
							(mid -0.249642 0.249642)
							(end -0.1778 0.2794)
						)
						(arc
							(start 0.1778 0.2794)
							(mid 0.249642 0.249642)
							(end 0.2794 0.1778)
						)
						(arc
							(start 0.2794 -0.1778)
							(mid 0.249642 -0.249642)
							(end 0.1778 -0.2794)
						)
					)
					(width 0)
					(fill yes)
				)
			)
		)
	)
	(footprint ""
		(layer "F.Cu")
		(at 77.4954 -167.5892)
		(property "Reference" "R539"
			(at 0 0 0)
			(layer "F.SilkS")
			(hide yes)
			(effects
				(font
					(size 1.27 1.27)
				)
			)
		)
		(property "Value" "10KR2F-2-GP"
			(at 0.064008 -3.993896 0)
			(unlocked yes)
			(layer "F.Fab")
			(hide yes)
			(effects
				(font
					(size 1.016 1.016)
					(thickness 0.1524)
				)
			)
		)
		(property "Device Type" "R402H16"
			(at 0.064008 -5.517896 0)
			(unlocked yes)
			(layer "F.Fab")
			(hide yes)
			(effects
				(font
					(size 1.016 1.016)
					(thickness 0.1524)
				)
			)
		)
		(duplicate_pad_numbers_are_jumpers no)
		(fp_line
			(start -0.508 -0.9398)
			(end -0.508 0.9398)
			(stroke
				(width 0.1524)
				(type default)
			)
			(layer "F.SilkS")
		)
		(fp_line
			(start 0.508 -0.9398)
			(end -0.508 -0.9398)
			(stroke
				(width 0.1524)
				(type default)
			)
			(layer "F.SilkS")
		)
		(fp_rect
			(start -0.508 0.9398)
			(end 0.508 -0.9398)
			(stroke
				(width 0)
				(type default)
			)
			(fill no)
			(layer "F.CrtYd")
		)
		(fp_rect
			(start -0.508 0.9398)
			(end 0.508 -0.9398)
			(stroke
				(width 0)
				(type default)
			)
			(fill no)
			(layer "F.Fab")
		)
		(pad "1" smd custom
			(at 0 -0.4445)
			(size 0.1397 0.1397)
			(layers "F.Cu" "F.Mask" "F.Paste")
			(net "P3V3_STBY")
			(options
				(clearance outline)
				(anchor circle)
			)
			(primitives
				(gr_poly
					(pts
						(arc
							(start -0.1778 -0.2794)
							(mid -0.249642 -0.249642)
							(end -0.2794 -0.1778)
						)
						(arc
							(start -0.2794 0.1778)
							(mid -0.249642 0.249642)
							(end -0.1778 0.2794)
						)
						(arc
							(start 0.1778 0.2794)
							(mid 0.249642 0.249642)
							(end 0.2794 0.1778)
						)
						(arc
							(start 0.2794 -0.1778)
							(mid 0.249642 -0.249642)
							(end 0.1778 -0.2794)
						)
					)
					(width 0)
					(fill yes)
				)
			)
		)
		(pad "2" smd custom
			(at 0 0.4445)
			(size 0.1397 0.1397)
			(layers "F.Cu" "F.Mask" "F.Paste")
			(net "P1V15_STBY_PG")
			(options
				(clearance outline)
				(anchor circle)
			)
			(primitives
				(gr_poly
					(pts
						(arc
							(start -0.1778 -0.2794)
							(mid -0.249642 -0.249642)
							(end -0.2794 -0.1778)
						)
						(arc
							(start -0.2794 0.1778)
							(mid -0.249642 0.249642)
							(end -0.1778 0.2794)
						)
						(arc
							(start 0.1778 0.2794)
							(mid 0.249642 0.249642)
							(end 0.2794 0.1778)
						)
						(arc
							(start 0.2794 -0.1778)
							(mid 0.249642 -0.249642)
							(end 0.1778 -0.2794)
						)
					)
					(width 0)
					(fill yes)
				)
			)
		)
	)
	(footprint ""
		(layer "F.Cu")
		(at 86.857586 -66.322448 90)
		(property "Reference" "R9"
			(at 0 0 90)
			(layer "F.SilkS")
			(hide yes)
			(effects
				(font
					(size 1.27 1.27)
				)
			)
		)
		(property "Value" "0R2J-2-GP"
			(at 0.064008 -3.993896 90)
			(unlocked yes)
			(layer "F.Fab")
			(hide yes)
			(effects
				(font
					(size 1.016 1.016)
					(thickness 0.1524)
				)
			)
		)
		(property "Device Type" "R402H16"
			(at 0.064008 -5.517896 90)
			(unlocked yes)
			(layer "F.Fab")
			(hide yes)
			(effects
				(font
					(size 1.016 1.016)
					(thickness 0.1524)
				)
			)
		)
		(duplicate_pad_numbers_are_jumpers no)
		(fp_line
			(start 0.508 -0.9398)
			(end -0.508 -0.9398)
			(stroke
				(width 0.1524)
				(type default)
			)
			(layer "F.SilkS")
		)
		(fp_line
			(start -0.508 -0.9398)
			(end -0.508 0.9398)
			(stroke
				(width 0.1524)
				(type default)
			)
			(layer "F.SilkS")
		)
		(fp_rect
			(start -0.508 0.9398)
			(end 0.508 -0.9398)
			(stroke
				(width 0)
				(type default)
			)
			(fill no)
			(layer "F.CrtYd")
		)
		(fp_rect
			(start -0.508 0.9398)
			(end 0.508 -0.9398)
			(stroke
				(width 0)
				(type default)
			)
			(fill no)
			(layer "F.Fab")
		)
		(pad "1" smd custom
			(at 0 -0.4445 90)
			(size 0.1397 0.1397)
			(layers "F.Cu" "F.Mask" "F.Paste")
			(net "NCSI_RX_ER_R")
			(options
				(clearance outline)
				(anchor circle)
			)
			(primitives
				(gr_poly
					(pts
						(arc
							(start -0.1778 -0.2794)
							(mid -0.249642 -0.249642)
							(end -0.2794 -0.1778)
						)
						(arc
							(start -0.2794 0.1778)
							(mid -0.249642 0.249642)
							(end -0.1778 0.2794)
						)
						(arc
							(start 0.1778 0.2794)
							(mid 0.249642 0.249642)
							(end 0.2794 0.1778)
						)
						(arc
							(start 0.2794 -0.1778)
							(mid 0.249642 -0.249642)
							(end 0.1778 -0.2794)
						)
					)
					(width 0)
					(fill yes)
				)
			)
		)
		(pad "2" smd custom
			(at 0 0.4445 90)
			(size 0.1397 0.1397)
			(layers "F.Cu" "F.Mask" "F.Paste")
			(net "NCSI_RX_ER")
			(options
				(clearance outline)
				(anchor circle)
			)
			(primitives
				(gr_poly
					(pts
						(arc
							(start -0.1778 -0.2794)
							(mid -0.249642 -0.249642)
							(end -0.2794 -0.1778)
						)
						(arc
							(start -0.2794 0.1778)
							(mid -0.249642 0.249642)
							(end -0.1778 0.2794)
						)
						(arc
							(start 0.1778 0.2794)
							(mid 0.249642 0.249642)
							(end 0.2794 0.1778)
						)
						(arc
							(start 0.2794 -0.1778)
							(mid 0.249642 -0.249642)
							(end 0.1778 -0.2794)
						)
					)
					(width 0)
					(fill yes)
				)
			)
		)
	)
)
